FILE_TYPE = CONNECTIVITY;
{Allegro Design Entry HDL 17.2-2016 S081 (4005846) 1/11/2022}
"PAGE_NUMBER" = 28;
0"NC";
1"DMI_CPU0_PCH_TX_DN<7:0>";
2"DMI_CPU0_PCH_TX_DP<7:0>";
3"DMI_CPU0_PCH_RX_C_DP<7:0>";
4"DMI_CPU0_PCH_RX_C_DN<7:0>";
5"DMI_CPU0_PCH_RX_C_DN<7>";
6"DMI_CPU0_PCH_RX_C_DP<6>";
7"DMI_CPU0_PCH_RX_C_DP<5>";
8"DMI_CPU0_PCH_RX_C_DP<4>";
9"DMI_CPU0_PCH_RX_C_DP<3>";
10"DMI_CPU0_PCH_RX_C_DN<2>";
11"DMI_CPU0_PCH_RX_C_DP<1>";
12"DMI_CPU0_PCH_RX_C_DN<0>";
13"DMI_CPU0_PCH_RX_C_DP<7>";
14"DMI_CPU0_PCH_RX_C_DN<6>";
15"DMI_CPU0_PCH_RX_C_DN<5>";
16"DMI_CPU0_PCH_RX_C_DN<4>";
17"DMI_CPU0_PCH_RX_C_DN<3>";
18"DMI_CPU0_PCH_RX_C_DP<2>";
19"DMI_CPU0_PCH_RX_C_DN<1>";
20"DMI_CPU0_PCH_RX_C_DP<0>";
21"DMI_CPU0_PCH_TX_DP<7>";
22"DMI_CPU0_PCH_TX_DN<6>"$PNN"DMI_CPU0_PCH_TX_DP<3>";
23"DMI_CPU0_PCH_TX_DN<5>";
24"DMI_CPU0_PCH_TX_DN<4>";
25"DMI_CPU0_PCH_TX_DP<3>";
26"DMI_CPU0_PCH_TX_DP<2>";
27"DMI_CPU0_PCH_TX_DP<1>";
28"DMI_CPU0_PCH_TX_DP<0>";
29"DMI_CPU0_PCH_TX_DN<7>";
30"DMI_CPU0_PCH_TX_DP<6>";
31"DMI_CPU0_PCH_TX_DP<5>";
32"DMI_CPU0_PCH_TX_DP<4>";
33"DMI_CPU0_PCH_TX_DN<3>"$PNN"DMI_CPU0_PCH_TX_DP<6>";
34"DMI_CPU0_PCH_TX_DN<2>";
35"DMI_CPU0_PCH_TX_DN<1>";
36"DMI_CPU0_PCH_TX_DN<0>";
%"TAP"
"1","(3400,3450)","0","standard","I151";
;
CDS_LIB"standard"
BODY_TYPE"PLUMBING"
HDL_TAP"TRUE";
"B \NAC \NWC"1;
"S \NAC"
BN"5"23;
%"TAP"
"1","(3400,3400)","0","standard","I152";
;
CDS_LIB"standard"
BODY_TYPE"PLUMBING"
HDL_TAP"TRUE";
"B \NAC \NWC"1;
"S \NAC"
BN"4"24;
%"TAP"
"1","(3150,3850)","0","standard","I161";
;
CDS_LIB"standard"
BODY_TYPE"PLUMBING"
HDL_TAP"TRUE";
"B \NAC \NWC"2;
"S \NAC"
BN"4"32;
%"TAP"
"1","(3150,3900)","0","standard","I165";
;
CDS_LIB"standard"
BODY_TYPE"PLUMBING"
HDL_TAP"TRUE";
"B \NAC \NWC"2;
"S \NAC"
BN"5"31;
%"SOCKET4677_AZIF0045P001C01CS"
"16","(1475,3600)","0","pure_quanta","I169";
;
PART_NUMBER"DGA^7000023"
VALUE"SOCKET4677_AZIF0045-P001C01CS"
MATERIAL"IO"
PART_TYPE"SMLF"
$LOCATION"U2"
CDS_LMAN_SYM_OUTLINE"-1050,550,1050,-550"
NEEDS_NO_SIZE"TRUE"
CDS_LIB"pure_quanta"
CDS_LOCATION"U2"
$SEC"16"
CDS_SEC"16";
"DMI_TX_DP0"
$PN"CA19"36;
"DMI_TX_DP1"
$PN"BY18"35;
"DMI_TX_DP2"
$PN"CC19"34;
"DMI_TX_DP3"
$PN"CD18"33;
"DMI_TX_DP4"
$PN"CG19"32;
"DMI_TX_DP5"
$PN"CH18"31;
"DMI_TX_DP6"
$PN"CL19"30;
"DMI_TX_DP7"
$PN"CM18"29;
"DMI_TX_DN0"
$PN"BW19"28;
"DMI_TX_DN1"
$PN"CA17"27;
"DMI_TX_DN2"
$PN"CB18"26;
"DMI_TX_DN3"
$PN"CE17"25;
"DMI_TX_DN4"
$PN"CF18"24;
"DMI_TX_DN5"
$PN"CJ17"23;
"DMI_TX_DN6"
$PN"CK18"22;
"DMI_TX_DN7"
$PN"CN17"21;
"DMI_RX_DP0"
$PN"BC19"20;
"DMI_RX_DP1"
$PN"BD18"19;
"DMI_RX_DP2"
$PN"BG19"18;
"DMI_RX_DP3"
$PN"BH18"17;
"DMI_RX_DP4"
$PN"BL19"16;
"DMI_RX_DP5"
$PN"BM18"15;
"DMI_RX_DP6"
$PN"BR19"14;
"DMI_RX_DP7"
$PN"BT18"13;
"DMI_RX_DN0"
$PN"BB18"12;
"DMI_RX_DN1"
$PN"BE17"11;
"DMI_RX_DN2"
$PN"BF18"10;
"DMI_RX_DN3"
$PN"BJ17"9;
"DMI_RX_DN4"
$PN"BK18"8;
"DMI_RX_DN5"
$PN"BN17"7;
"DMI_RX_DN6"
$PN"BP18"6;
"DMI_RX_DN7"
$PN"BU17"5;
%"TAP"
"1","(-475,3300)","2","standard","I171";
;
CDS_LIB"standard"
BODY_TYPE"PLUMBING"
HDL_TAP"TRUE";
"B \NAC \NWC"4;
"S \NAC"
BN"2"10;
%"TAP"
"1","(-475,3200)","2","standard","I173";
;
CDS_LIB"standard"
BODY_TYPE"PLUMBING"
HDL_TAP"TRUE";
"B \NAC \NWC"4;
"S \NAC"
BN"0"12;
%"TAP"
"1","(-225,4000)","2","standard","I179";
;
CDS_LIB"standard"
BODY_TYPE"PLUMBING"
HDL_TAP"TRUE";
"B \NAC \NWC"3;
"S \NAC"
BN"7"13;
%"TAP"
"1","(-225,3750)","2","standard","I184";
;
CDS_LIB"standard"
BODY_TYPE"PLUMBING"
HDL_TAP"TRUE";
"B \NAC \NWC"3;
"S \NAC"
BN"2"18;
%"TAP"
"1","(-225,3650)","2","standard","I186";
;
CDS_LIB"standard"
BODY_TYPE"PLUMBING"
HDL_TAP"TRUE";
"B \NAC \NWC"3;
"S \NAC"
BN"0"20;
%"TAP"
"1","(-475,3550)","2","standard","I188";
;
CDS_LIB"standard"
BODY_TYPE"PLUMBING"
HDL_TAP"TRUE";
"B \NAC \NWC"4;
"S \NAC"
BN"7"5;
%"TAP"
"1","(3400,3650)","0","standard","I288";
;
CDS_LIB"standard"
BODY_TYPE"PLUMBING"
HDL_TAP"TRUE";
"B \NAC \NWC"1;
"S \NAC"
BN"0"36;
%"TAP"
"1","(3400,3700)","0","standard","I289";
;
CDS_LIB"standard"
BODY_TYPE"PLUMBING"
HDL_TAP"TRUE";
"B \NAC \NWC"1;
"S \NAC"
BN"1"35;
%"TAP"
"1","(3400,3750)","0","standard","I290";
;
CDS_LIB"standard"
BODY_TYPE"PLUMBING"
HDL_TAP"TRUE";
"B \NAC \NWC"1;
"S \NAC"
BN"2"34;
%"TAP"
"1","(3400,4000)","0","standard","I292";
;
CDS_LIB"standard"
BODY_TYPE"PLUMBING"
HDL_TAP"TRUE";
"B \NAC \NWC"1;
"S \NAC"
BN"7"29;
%"TAP"
"1","(3150,3250)","0","standard","I293";
;
CDS_LIB"standard"
BODY_TYPE"PLUMBING"
HDL_TAP"TRUE";
"B \NAC \NWC"2;
"S \NAC"
BN"1"27;
%"TAP"
"1","(3150,3300)","0","standard","I294";
;
CDS_LIB"standard"
BODY_TYPE"PLUMBING"
HDL_TAP"TRUE";
"B \NAC \NWC"2;
"S \NAC"
BN"2"26;
%"TAP"
"1","(3150,3550)","0","standard","I296";
;
CDS_LIB"standard"
BODY_TYPE"PLUMBING"
HDL_TAP"TRUE";
"B \NAC \NWC"2;
"S \NAC"
BN"7"21;
%"TAP"
"1","(3150,3200)","0","standard","I297";
;
CDS_LIB"standard"
BODY_TYPE"PLUMBING"
HDL_TAP"TRUE";
"B \NAC \NWC"2;
"S \NAC"
BN"0"28;
%"TAP"
"1","(-475,3950)","2","standard","I298";
;
CDS_LIB"standard"
BODY_TYPE"PLUMBING"
HDL_TAP"TRUE";
"B \NAC \NWC"4;
"S \NAC"
BN"6"14;
%"TAP"
"1","(-475,3900)","2","standard","I299";
;
CDS_LIB"standard"
BODY_TYPE"PLUMBING"
HDL_TAP"TRUE";
"B \NAC \NWC"4;
"S \NAC"
BN"5"15;
%"TAP"
"1","(-475,3850)","2","standard","I300";
;
CDS_LIB"standard"
BODY_TYPE"PLUMBING"
HDL_TAP"TRUE";
"B \NAC \NWC"4;
"S \NAC"
BN"4"16;
%"TAP"
"1","(-475,3800)","2","standard","I301";
;
CDS_LIB"standard"
BODY_TYPE"PLUMBING"
HDL_TAP"TRUE";
"B \NAC \NWC"4;
"S \NAC"
BN"3"17;
%"TAP"
"1","(-475,3700)","2","standard","I302";
;
CDS_LIB"standard"
BODY_TYPE"PLUMBING"
HDL_TAP"TRUE";
"B \NAC \NWC"4;
"S \NAC"
BN"1"19;
%"TAP"
"1","(-225,3500)","2","standard","I303";
;
CDS_LIB"standard"
BODY_TYPE"PLUMBING"
HDL_TAP"TRUE";
"B \NAC \NWC"3;
"S \NAC"
BN"6"6;
%"TAP"
"1","(-225,3450)","2","standard","I304";
;
CDS_LIB"standard"
BODY_TYPE"PLUMBING"
HDL_TAP"TRUE";
"B \NAC \NWC"3;
"S \NAC"
BN"5"7;
%"TAP"
"1","(-225,3400)","2","standard","I305";
;
CDS_LIB"standard"
BODY_TYPE"PLUMBING"
HDL_TAP"TRUE";
"B \NAC \NWC"3;
"S \NAC"
BN"4"8;
%"TAP"
"1","(-225,3350)","2","standard","I306";
;
CDS_LIB"standard"
BODY_TYPE"PLUMBING"
HDL_TAP"TRUE";
"B \NAC \NWC"3;
"S \NAC"
BN"3"9;
%"TAP"
"1","(-225,3250)","2","standard","I307";
;
CDS_LIB"standard"
BODY_TYPE"PLUMBING"
HDL_TAP"TRUE";
"B \NAC \NWC"3;
"S \NAC"
BN"1"11;
%"TAP"
"1","(3400,3500)","0","standard","I308";
;
CDS_LIB"standard"
BODY_TYPE"PLUMBING"
HDL_TAP"TRUE";
"B \NAC \NWC"1;
"S \NAC"
BN"6"22;
%"TAP"
"1","(3150,3950)","0","standard","I309";
;
CDS_LIB"standard"
BODY_TYPE"PLUMBING"
HDL_TAP"TRUE";
"B \NAC \NWC"2;
"S \NAC"
BN"6"30;
%"TAP"
"1","(3150,3350)","0","standard","I310";
;
CDS_LIB"standard"
BODY_TYPE"PLUMBING"
HDL_TAP"TRUE";
"B \NAC \NWC"2;
"S \NAC"
BN"3"25;
%"TAP"
"1","(3400,3800)","0","standard","I311";
;
CDS_LIB"standard"
BODY_TYPE"PLUMBING"
HDL_TAP"TRUE";
"B \NAC \NWC"1;
"S \NAC"
BN"3"33;
END.
